# T6G (Grand Teton) — schematic netlist excerpt (pin names and nets, part order shuffled) for the footprints in the layout excerpt that follows; sources: Cadence DE-HDL packaged netlist, KiCad conversion of 04192023_DAF0TMB3IC0_F0TG_MB_C_brd_V02_OCP.brd

PR6560  Q_RES  2.2 5% CHIP  pkg 0402LF  page 363 : A = P0V9_RETIMER_CPU0_PVCC ; B = P0V9_RETIMER_CPU0_VCC2
C2175  Q_CAP  22UF 4V 20% X6S  pkg C0402  page 69 : A = PVDDCR_CPU0_P0 ; B = GND

(kicad_pcb
	(version 20260206)
	(generator "pcbnew")
	(generator_version "10.0")
	(general
		(thickness 1.6)
		(legacy_teardrops no)
	)
	(paper "A4")
	(title_block
		(title "04192023_DAF0TMB3IC0_F0TG_MB_C_brd_V02_OCP.brd")
		(comment 1 "Grand Teton / footprints 6679-6680 of 8354")
	)
	(layers
		(0 "F.Cu" signal "TOP")
		(4 "In1.Cu" signal "GND")
		(6 "In2.Cu" signal "IN1")
		(8 "In3.Cu" signal "GND1")
		(10 "In4.Cu" signal "IN2")
		(12 "In5.Cu" signal "GND2")
		(14 "In6.Cu" signal "IN3")
		(16 "In7.Cu" signal "GND3")
		(18 "In8.Cu" signal "VCC")
		(20 "In9.Cu" signal "VCC1")
		(22 "In10.Cu" signal "GND4")
		(24 "In11.Cu" signal "IN4")
		(26 "In12.Cu" signal "GND5")
		(28 "In13.Cu" signal "IN5")
		(30 "In14.Cu" signal "GND6")
		(32 "In15.Cu" signal "IN6")
		(34 "In16.Cu" signal "GND7")
		(2 "B.Cu" signal "BOTTOM")
		(9 "F.Adhes" user "F.Adhesive")
		(11 "B.Adhes" user "B.Adhesive")
		(13 "F.Paste" user "Package Geometry/Pastemask Top")
		(15 "B.Paste" user "Package Geometry/Pastemask Bottom")
		(5 "F.SilkS" user "Ref Des/Silkscreen Top")
		(7 "B.SilkS" user "Ref Des/Silkscreen Bottom")
		(1 "F.Mask" user "Board Geometry/Soldermask Top")
		(3 "B.Mask" user "Board Geometry/Soldermask Bottom")
		(17 "Dwgs.User" user "User.Drawings")
		(19 "Cmts.User" user "User.Comments")
		(21 "Eco1.User" user "User.Eco1")
		(23 "Eco2.User" user "User.Eco2")
		(25 "Edge.Cuts" user "Board Geometry/Outline")
		(27 "Margin" user)
		(31 "F.CrtYd" user "Package Geometry/Place Bound Top")
		(29 "B.CrtYd" user "Package Geometry/Place Bound Bottom")
		(35 "F.Fab" user "Ref Des/Assembly Top")
		(33 "B.Fab" user "Ref Des/Assembly Bottom")
	)
	(footprint ""
		(layer "B.Cu")
		(at 362.051346 -249.36831)
		(property "Reference" "C2175"
			(at 0 0 0)
			(layer "B.SilkS")
			(hide yes)
			(effects
				(font
					(size 1.27 1.27)
				)
				(justify mirror)
			)
		)
		(property "Value" ""
			(at 0 0 0)
			(layer "B.Fab")
			(effects
				(font
					(size 1.27 1.27)
				)
				(justify mirror)
			)
		)
		(duplicate_pad_numbers_are_jumpers no)
		(fp_line
			(start -0.7874 -0.4064)
			(end -0.7874 0.4064)
			(stroke
				(width 0.1524)
				(type default)
			)
			(layer "B.SilkS")
		)
		(fp_line
			(start -0.7874 0.4064)
			(end 0.7874 0.4064)
			(stroke
				(width 0.1524)
				(type default)
			)
			(layer "B.SilkS")
		)
		(fp_line
			(start 0.7874 -0.4064)
			(end -0.7874 -0.4064)
			(stroke
				(width 0.1524)
				(type default)
			)
			(layer "B.SilkS")
		)
		(fp_line
			(start 0.7874 0.4064)
			(end 0.7874 -0.4064)
			(stroke
				(width 0.1524)
				(type default)
			)
			(layer "B.SilkS")
		)
		(fp_line
			(start -0.67945 -0.3048)
			(end -0.67945 0.3048)
			(stroke
				(width 0.1)
				(type default)
			)
			(layer "B.Fab")
		)
		(fp_line
			(start -0.67945 0.3048)
			(end -0.120396 0.3048)
			(stroke
				(width 0.1)
				(type default)
			)
			(layer "B.Fab")
		)
		(fp_line
			(start -0.12065 -0.3048)
			(end -0.67945 -0.3048)
			(stroke
				(width 0.1)
				(type default)
			)
			(layer "B.Fab")
		)
		(fp_line
			(start -0.12065 -0.2794)
			(end -0.12065 -0.3048)
			(stroke
				(width 0.1)
				(type default)
			)
			(layer "B.Fab")
		)
		(fp_line
			(start -0.120396 0.2794)
			(end 0.12065 0.2794)
			(stroke
				(width 0.1)
				(type default)
			)
			(layer "B.Fab")
		)
		(fp_line
			(start -0.120396 0.3048)
			(end -0.120396 0.2794)
			(stroke
				(width 0.1)
				(type default)
			)
			(layer "B.Fab")
		)
		(fp_line
			(start 0.12065 -0.305054)
			(end 0.12065 -0.2794)
			(stroke
				(width 0.1)
				(type default)
			)
			(layer "B.Fab")
		)
		(fp_line
			(start 0.12065 -0.2794)
			(end -0.12065 -0.2794)
			(stroke
				(width 0.1)
				(type default)
			)
			(layer "B.Fab")
		)
		(fp_line
			(start 0.12065 0.2794)
			(end 0.12065 0.3048)
			(stroke
				(width 0.1)
				(type default)
			)
			(layer "B.Fab")
		)
		(fp_line
			(start 0.12065 0.3048)
			(end 0.67945 0.3048)
			(stroke
				(width 0.1)
				(type default)
			)
			(layer "B.Fab")
		)
		(fp_line
			(start 0.67945 -0.305054)
			(end 0.12065 -0.305054)
			(stroke
				(width 0.1)
				(type default)
			)
			(layer "B.Fab")
		)
		(fp_line
			(start 0.67945 0.3048)
			(end 0.67945 -0.305054)
			(stroke
				(width 0.1)
				(type default)
			)
			(layer "B.Fab")
		)
		(pad "1" smd circle
			(at 0.40005 0 180)
			(size 0 0)
			(layers "B.Cu" "B.Mask" "B.Paste")
			(net "PVDDCR_CPU0_P0")
		)
		(pad "2" smd circle
			(at -0.40005 0 180)
			(size 0 0)
			(layers "B.Cu" "B.Mask" "B.Paste")
			(net "GND")
		)
	)
	(footprint ""
		(layer "B.Cu")
		(at 450.666866 -397.91767 -90)
		(property "Reference" "PR6560"
			(at 0 0 90)
			(layer "B.SilkS")
			(hide yes)
			(effects
				(font
					(size 1.27 1.27)
				)
				(justify mirror)
			)
		)
		(property "Value" ""
			(at 0 0 90)
			(layer "B.Fab")
			(effects
				(font
					(size 1.27 1.27)
				)
				(justify mirror)
			)
		)
		(duplicate_pad_numbers_are_jumpers no)
		(fp_line
			(start -0.7874 0.4064)
			(end 0.7874 0.4064)
			(stroke
				(width 0.1524)
				(type default)
			)
			(layer "B.SilkS")
		)
		(fp_line
			(start 0.7874 0.4064)
			(end 0.7874 -0.4064)
			(stroke
				(width 0.1524)
				(type default)
			)
			(layer "B.SilkS")
		)
		(fp_line
			(start -0.7874 -0.4064)
			(end -0.7874 0.4064)
			(stroke
				(width 0.1524)
				(type default)
			)
			(layer "B.SilkS")
		)
		(fp_line
			(start 0.7874 -0.4064)
			(end -0.7874 -0.4064)
			(stroke
				(width 0.1524)
				(type default)
			)
			(layer "B.SilkS")
		)
		(fp_line
			(start -0.67945 0.3048)
			(end -0.120396 0.3048)
			(stroke
				(width 0.1)
				(type default)
			)
			(layer "B.Fab")
		)
		(fp_line
			(start -0.120396 0.3048)
			(end -0.120396 0.2794)
			(stroke
				(width 0.1)
				(type default)
			)
			(layer "B.Fab")
		)
		(fp_line
			(start 0.12065 0.3048)
			(end 0.67945 0.3048)
			(stroke
				(width 0.1)
				(type default)
			)
			(layer "B.Fab")
		)
		(fp_line
			(start 0.67945 0.3048)
			(end 0.67945 -0.305054)
			(stroke
				(width 0.1)
				(type default)
			)
			(layer "B.Fab")
		)
		(fp_line
			(start -0.120396 0.2794)
			(end 0.12065 0.2794)
			(stroke
				(width 0.1)
				(type default)
			)
			(layer "B.Fab")
		)
		(fp_line
			(start 0.12065 0.2794)
			(end 0.12065 0.3048)
			(stroke
				(width 0.1)
				(type default)
			)
			(layer "B.Fab")
		)
		(fp_line
			(start -0.12065 -0.2794)
			(end -0.12065 -0.3048)
			(stroke
				(width 0.1)
				(type default)
			)
			(layer "B.Fab")
		)
		(fp_line
			(start 0.12065 -0.2794)
			(end -0.12065 -0.2794)
			(stroke
				(width 0.1)
				(type default)
			)
			(layer "B.Fab")
		)
		(fp_line
			(start -0.67945 -0.3048)
			(end -0.67945 0.3048)
			(stroke
				(width 0.1)
				(type default)
			)
			(layer "B.Fab")
		)
		(fp_line
			(start -0.12065 -0.3048)
			(end -0.67945 -0.3048)
			(stroke
				(width 0.1)
				(type default)
			)
			(layer "B.Fab")
		)
		(fp_line
			(start 0.12065 -0.305054)
			(end 0.12065 -0.2794)
			(stroke
				(width 0.1)
				(type default)
			)
			(layer "B.Fab")
		)
		(fp_line
			(start 0.67945 -0.305054)
			(end 0.12065 -0.305054)
			(stroke
				(width 0.1)
				(type default)
			)
			(layer "B.Fab")
		)
		(pad "1" smd circle
			(at 0.40005 0 90)
			(size 0 0)
			(layers "B.Cu" "B.Mask" "B.Paste")
			(net "P0V9_RETIMER_CPU0_PVCC")
		)
		(pad "2" smd circle
			(at -0.40005 0 90)
			(size 0 0)
			(layers "B.Cu" "B.Mask" "B.Paste")
			(net "P0V9_RETIMER_CPU0_VCC2")
		)
	)
)
